(kicad_pcb
	(version 20260206)
	(generator "pcbnew")
	(generator_version "10.0")
	(general
		(thickness 1.6)
		(legacy_teardrops no)
	)
	(paper "A4")
	(title_block
		(title "Bryce Canyon_SCC_16316-1_OCP.brd")
		(comment 1 "Bryce Canyon / footprints 191-198 of 1561")
	)
	(layers
		(0 "F.Cu" signal "TOP")
		(4 "In1.Cu" signal "L2GND")
		(6 "In2.Cu" signal "L3")
		(8 "In3.Cu" signal "L4VCC")
		(10 "In4.Cu" signal "L5VCC")
		(12 "In5.Cu" signal "L6")
		(14 "In6.Cu" signal "L7GND")
		(2 "B.Cu" signal "BOTTOM")
		(9 "F.Adhes" user "F.Adhesive")
		(11 "B.Adhes" user "B.Adhesive")
		(13 "F.Paste" user "Package Geometry/Pastemask Top")
		(15 "B.Paste" user "Package Geometry/Pastemask Bottom")
		(5 "F.SilkS" user "Ref Des/Silkscreen Top")
		(7 "B.SilkS" user "Ref Des/Silkscreen Bottom")
		(1 "F.Mask" user "Board Geometry/Soldermask Top")
		(3 "B.Mask" user "Board Geometry/Soldermask Bottom")
		(17 "Dwgs.User" user "User.Drawings")
		(19 "Cmts.User" user "User.Comments")
		(21 "Eco1.User" user "User.Eco1")
		(23 "Eco2.User" user "User.Eco2")
		(25 "Edge.Cuts" user "Board Geometry/Outline")
		(27 "Margin" user)
		(31 "F.CrtYd" user "Package Geometry/Place Bound Top")
		(29 "B.CrtYd" user "Package Geometry/Place Bound Bottom")
		(35 "F.Fab" user "Ref Des/Assembly Top")
		(33 "B.Fab" user "Ref Des/Assembly Bottom")
	)
	(footprint ""
		(layer "F.Cu")
		(at 149.9489 -83.5025 180)
		(property "Reference" "R321"
			(at 0 0 180)
			(layer "F.SilkS")
			(hide yes)
			(effects
				(font
					(size 1.27 1.27)
				)
			)
		)
		(property "Value" "1KR2F-3-GP"
			(at 0.064008 -3.993896 180)
			(unlocked yes)
			(layer "F.Fab")
			(hide yes)
			(effects
				(font
					(size 1.016 1.016)
					(thickness 0.1524)
				)
			)
		)
		(property "Device Type" "R402H16"
			(at 0.064008 -5.517896 180)
			(unlocked yes)
			(layer "F.Fab")
			(hide yes)
			(effects
				(font
					(size 1.016 1.016)
					(thickness 0.1524)
				)
			)
		)
		(duplicate_pad_numbers_are_jumpers no)
		(fp_line
			(start 0.508 -0.9398)
			(end -0.508 -0.9398)
			(stroke
				(width 0.1524)
				(type default)
			)
			(layer "F.SilkS")
		)
		(fp_line
			(start -0.508 -0.9398)
			(end -0.508 0.9398)
			(stroke
				(width 0.1524)
				(type default)
			)
			(layer "F.SilkS")
		)
		(fp_rect
			(start -0.508 0.9398)
			(end 0.508 -0.9398)
			(stroke
				(width 0)
				(type default)
			)
			(fill no)
			(layer "F.CrtYd")
		)
		(fp_rect
			(start -0.508 0.9398)
			(end 0.508 -0.9398)
			(stroke
				(width 0)
				(type default)
			)
			(fill no)
			(layer "F.Fab")
		)
		(pad "1" smd custom
			(at 0 -0.4445 180)
			(size 0.1397 0.1397)
			(layers "F.Cu" "F.Mask" "F.Paste")
			(net "P1V8_E")
			(options
				(clearance outline)
				(anchor circle)
			)
			(primitives
				(gr_poly
					(pts
						(arc
							(start -0.1778 -0.2794)
							(mid -0.249642 -0.249642)
							(end -0.2794 -0.1778)
						)
						(arc
							(start -0.2794 0.1778)
							(mid -0.249642 0.249642)
							(end -0.1778 0.2794)
						)
						(arc
							(start 0.1778 0.2794)
							(mid 0.249642 0.249642)
							(end 0.2794 0.1778)
						)
						(arc
							(start 0.2794 -0.1778)
							(mid 0.249642 -0.249642)
							(end 0.1778 -0.2794)
						)
					)
					(width 0)
					(fill yes)
				)
			)
		)
		(pad "2" smd custom
			(at 0 0.4445 180)
			(size 0.1397 0.1397)
			(layers "F.Cu" "F.Mask" "F.Paste")
			(net "P1V8_E_SENSE")
			(options
				(clearance outline)
				(anchor circle)
			)
			(primitives
				(gr_poly
					(pts
						(arc
							(start -0.1778 -0.2794)
							(mid -0.249642 -0.249642)
							(end -0.2794 -0.1778)
						)
						(arc
							(start -0.2794 0.1778)
							(mid -0.249642 0.249642)
							(end -0.1778 0.2794)
						)
						(arc
							(start 0.1778 0.2794)
							(mid 0.249642 0.249642)
							(end 0.2794 0.1778)
						)
						(arc
							(start 0.2794 -0.1778)
							(mid 0.249642 -0.249642)
							(end 0.1778 -0.2794)
						)
					)
					(width 0)
					(fill yes)
				)
			)
		)
	)
	(footprint ""
		(layer "F.Cu")
		(at 40.9702 -43.4086)
		(property "Reference" "C667"
			(at 0 0 0)
			(layer "F.SilkS")
			(hide yes)
			(effects
				(font
					(size 1.27 1.27)
				)
			)
		)
		(property "Value" "SC10U16V5KX-7-GP-U"
			(at -0.0762 -6.1214 0)
			(unlocked yes)
			(layer "F.Fab")
			(hide yes)
			(effects
				(font
					(size 1.016 1.016)
					(thickness 0.1524)
				)
			)
		)
		(property "Device Type" "C805H58"
			(at -0.0762 -8.1534 0)
			(unlocked yes)
			(layer "F.Fab")
			(hide yes)
			(effects
				(font
					(size 1.016 1.016)
					(thickness 0.1524)
				)
			)
		)
		(duplicate_pad_numbers_are_jumpers no)
		(fp_line
			(start 0.635 0)
			(end -0.635 0)
			(stroke
				(width 0.508)
				(type default)
			)
			(layer "F.SilkS")
		)
		(fp_rect
			(start -0.9652 1.778)
			(end 0.9652 -1.778)
			(stroke
				(width 0)
				(type default)
			)
			(fill no)
			(layer "F.CrtYd")
		)
		(fp_poly
			(pts
				(xy -0.9652 -1.778) (xy 0.9652 -1.778) (xy 0.9652 1.778) (xy -0.9652 1.778)
			)
			(stroke
				(width 0)
				(type default)
			)
			(fill no)
			(layer "F.Fab")
		)
		(pad "1" smd rect
			(at 0 -0.9652)
			(size 1.397 1.143)
			(layers "F.Cu" "F.Mask" "F.Paste")
			(net "P12V_STBY_VIN_Q7")
		)
		(pad "2" smd rect
			(at 0 0.9652)
			(size 1.397 1.143)
			(layers "F.Cu" "F.Mask" "F.Paste")
			(net "GND")
		)
	)
	(footprint ""
		(layer "F.Cu")
		(at 121.487692 -90.564716 180)
		(property "Reference" "R206"
			(at 0 0 180)
			(layer "F.SilkS")
			(hide yes)
			(effects
				(font
					(size 1.27 1.27)
				)
			)
		)
		(property "Value" "0R2J-2-GP"
			(at 0.064008 -3.993896 180)
			(unlocked yes)
			(layer "F.Fab")
			(hide yes)
			(effects
				(font
					(size 1.016 1.016)
					(thickness 0.1524)
				)
			)
		)
		(property "Device Type" "R402H16"
			(at 0.064008 -5.517896 180)
			(unlocked yes)
			(layer "F.Fab")
			(hide yes)
			(effects
				(font
					(size 1.016 1.016)
					(thickness 0.1524)
				)
			)
		)
		(duplicate_pad_numbers_are_jumpers no)
		(fp_line
			(start 0.508 -0.9398)
			(end -0.508 -0.9398)
			(stroke
				(width 0.1524)
				(type default)
			)
			(layer "F.SilkS")
		)
		(fp_line
			(start -0.508 -0.9398)
			(end -0.508 0.9398)
			(stroke
				(width 0.1524)
				(type default)
			)
			(layer "F.SilkS")
		)
		(fp_rect
			(start -0.508 0.9398)
			(end 0.508 -0.9398)
			(stroke
				(width 0)
				(type default)
			)
			(fill no)
			(layer "F.CrtYd")
		)
		(fp_rect
			(start -0.508 0.9398)
			(end 0.508 -0.9398)
			(stroke
				(width 0)
				(type default)
			)
			(fill no)
			(layer "F.Fab")
		)
		(pad "1" smd custom
			(at 0 -0.4445 180)
			(size 0.1397 0.1397)
			(layers "F.Cu" "F.Mask" "F.Paste")
			(net "BMC_EXP_SPARE_1_R_LS")
			(options
				(clearance outline)
				(anchor circle)
			)
			(primitives
				(gr_poly
					(pts
						(arc
							(start -0.1778 -0.2794)
							(mid -0.249642 -0.249642)
							(end -0.2794 -0.1778)
						)
						(arc
							(start -0.2794 0.1778)
							(mid -0.249642 0.249642)
							(end -0.1778 0.2794)
						)
						(arc
							(start 0.1778 0.2794)
							(mid 0.249642 0.249642)
							(end 0.2794 0.1778)
						)
						(arc
							(start 0.2794 -0.1778)
							(mid 0.249642 -0.249642)
							(end 0.1778 -0.2794)
						)
					)
					(width 0)
					(fill yes)
				)
			)
		)
		(pad "2" smd custom
			(at 0 0.4445 180)
			(size 0.1397 0.1397)
			(layers "F.Cu" "F.Mask" "F.Paste")
			(net "BMC_SPARE_1_LS")
			(options
				(clearance outline)
				(anchor circle)
			)
			(primitives
				(gr_poly
					(pts
						(arc
							(start -0.1778 -0.2794)
							(mid -0.249642 -0.249642)
							(end -0.2794 -0.1778)
						)
						(arc
							(start -0.2794 0.1778)
							(mid -0.249642 0.249642)
							(end -0.1778 0.2794)
						)
						(arc
							(start 0.1778 0.2794)
							(mid 0.249642 0.249642)
							(end 0.2794 0.1778)
						)
						(arc
							(start 0.2794 -0.1778)
							(mid 0.249642 -0.249642)
							(end 0.1778 -0.2794)
						)
					)
					(width 0)
					(fill yes)
				)
			)
		)
	)
	(footprint ""
		(layer "F.Cu")
		(at 148.745702 -40.794432 -78)
		(property "Reference" "VIA20"
			(at 0 0 282)
			(layer "F.SilkS")
			(hide yes)
			(effects
				(font
					(size 1.27 1.27)
				)
			)
		)
		(property "Value" "100OHM-8L-1D6MM-L13-GP"
			(at 3.289333 0.050849 282)
			(unlocked yes)
			(layer "F.Fab")
			(hide yes)
			(effects
				(font
					(size 1.016 1.016)
					(thickness 0.1524)
				)
			)
		)
		(property "Device Type" "VIA-PCIE-4P-409091"
			(at 3.289456 -1.473155 282)
			(unlocked yes)
			(layer "F.Fab")
			(hide yes)
			(effects
				(font
					(size 1.016 1.016)
					(thickness 0.1524)
				)
			)
		)
		(duplicate_pad_numbers_are_jumpers no)
		(fp_poly
			(pts
				(xy -2.044719 -0.457296) (xy 2.04468 -0.457296) (xy 2.044681 0.457104) (xy -2.044719 0.457104)
			)
			(stroke
				(width 0)
				(type default)
			)
			(fill no)
			(layer "F.CrtYd")
		)
		(fp_poly
			(pts
				(xy -2.044719 -0.457296) (xy 2.04468 -0.457296) (xy 2.044681 0.457104) (xy -2.044719 0.457104)
			)
			(stroke
				(width 0)
				(type default)
			)
			(fill no)
			(layer "F.Fab")
		)
		(pad "1" thru_hole circle
			(at -1.5875 0 282)
			(size 0.508 0.508)
			(drill 0.254)
			(layers "*.Cu" "*.Mask")
			(remove_unused_layers no)
			(net "GND")
			(clearance 0.2032)
			(thermal_gap 0.2032)
		)
		(pad "2" thru_hole circle
			(at -0.5715 0.000001 282)
			(size 0.508 0.508)
			(drill 0.254)
			(layers "*.Cu" "*.Mask")
			(remove_unused_layers no)
			(net "PHY_SCC_TO_IOC_C_43_DP")
			(clearance 0.2032)
			(thermal_gap 0.2032)
		)
		(pad "3" thru_hole circle
			(at 0.5715 -0.000001 282)
			(size 0.508 0.508)
			(drill 0.254)
			(layers "*.Cu" "*.Mask")
			(remove_unused_layers no)
			(net "PHY_SCC_TO_IOC_C_43_DN")
			(clearance 0.2032)
			(thermal_gap 0.2032)
		)
		(pad "4" thru_hole circle
			(at 1.5875 0 282)
			(size 0.508 0.508)
			(drill 0.254)
			(layers "*.Cu" "*.Mask")
			(remove_unused_layers no)
			(net "GND")
			(clearance 0.2032)
			(thermal_gap 0.2032)
		)
	)
	(footprint ""
		(layer "F.Cu")
		(at 157.8737 -80.007714 -90)
		(property "Reference" "R332"
			(at 0 0 270)
			(layer "F.SilkS")
			(hide yes)
			(effects
				(font
					(size 1.27 1.27)
				)
			)
		)
		(property "Value" "4K7R2F-GP"
			(at 0.064008 -3.993896 270)
			(unlocked yes)
			(layer "F.Fab")
			(hide yes)
			(effects
				(font
					(size 1.016 1.016)
					(thickness 0.1524)
				)
			)
		)
		(property "Device Type" "R402H16"
			(at 0.064008 -5.517896 270)
			(unlocked yes)
			(layer "F.Fab")
			(hide yes)
			(effects
				(font
					(size 1.016 1.016)
					(thickness 0.1524)
				)
			)
		)
		(duplicate_pad_numbers_are_jumpers no)
		(fp_line
			(start -0.508 -0.9398)
			(end -0.508 0.9398)
			(stroke
				(width 0.1524)
				(type default)
			)
			(layer "F.SilkS")
		)
		(fp_line
			(start 0.508 -0.9398)
			(end -0.508 -0.9398)
			(stroke
				(width 0.1524)
				(type default)
			)
			(layer "F.SilkS")
		)
		(fp_rect
			(start -0.508 0.9398)
			(end 0.508 -0.9398)
			(stroke
				(width 0)
				(type default)
			)
			(fill no)
			(layer "F.CrtYd")
		)
		(fp_rect
			(start -0.508 0.9398)
			(end 0.508 -0.9398)
			(stroke
				(width 0)
				(type default)
			)
			(fill no)
			(layer "F.Fab")
		)
		(pad "1" smd custom
			(at 0 -0.4445 270)
			(size 0.1397 0.1397)
			(layers "F.Cu" "F.Mask" "F.Paste")
			(net "P3V3")
			(options
				(clearance outline)
				(anchor circle)
			)
			(primitives
				(gr_poly
					(pts
						(arc
							(start -0.1778 -0.2794)
							(mid -0.249642 -0.249642)
							(end -0.2794 -0.1778)
						)
						(arc
							(start -0.2794 0.1778)
							(mid -0.249642 0.249642)
							(end -0.1778 0.2794)
						)
						(arc
							(start 0.1778 0.2794)
							(mid 0.249642 0.249642)
							(end 0.2794 0.1778)
						)
						(arc
							(start 0.2794 -0.1778)
							(mid 0.249642 -0.249642)
							(end 0.1778 -0.2794)
						)
					)
					(width 0)
					(fill yes)
				)
			)
		)
		(pad "2" smd custom
			(at 0 0.4445 270)
			(size 0.1397 0.1397)
			(layers "F.Cu" "F.Mask" "F.Paste")
			(net "VOL_SEN2_ADDR")
			(options
				(clearance outline)
				(anchor circle)
			)
			(primitives
				(gr_poly
					(pts
						(arc
							(start -0.1778 -0.2794)
							(mid -0.249642 -0.249642)
							(end -0.2794 -0.1778)
						)
						(arc
							(start -0.2794 0.1778)
							(mid -0.249642 0.249642)
							(end -0.1778 0.2794)
						)
						(arc
							(start 0.1778 0.2794)
							(mid 0.249642 0.249642)
							(end 0.2794 0.1778)
						)
						(arc
							(start 0.2794 -0.1778)
							(mid 0.249642 -0.249642)
							(end 0.1778 -0.2794)
						)
					)
					(width 0)
					(fill yes)
				)
			)
		)
	)
	(footprint ""
		(layer "F.Cu")
		(at 142.99311 -58.3057 -90)
		(property "Reference" "C40"
			(at 0 0 270)
			(layer "F.SilkS")
			(hide yes)
			(effects
				(font
					(size 1.27 1.27)
				)
			)
		)
		(property "Value" "SCD01U16V1KX-GP"
			(at -2.8321 -1.7399 270)
			(unlocked yes)
			(layer "F.Fab")
			(hide yes)
			(effects
				(font
					(size 1.016 1.016)
					(thickness 0.1524)
				)
			)
		)
		(property "Device Type" "C0201H13"
			(at -2.8321 -3.2639 270)
			(unlocked yes)
			(layer "F.Fab")
			(hide yes)
			(effects
				(font
					(size 1.016 1.016)
					(thickness 0.1524)
				)
			)
		)
		(duplicate_pad_numbers_are_jumpers no)
		(fp_rect
			(start -0.2794 0.6477)
			(end 0.2794 -0.6477)
			(stroke
				(width 0)
				(type default)
			)
			(fill no)
			(layer "F.CrtYd")
		)
		(fp_rect
			(start -0.2794 0.6477)
			(end 0.2794 -0.6477)
			(stroke
				(width 0)
				(type default)
			)
			(fill no)
			(layer "F.Fab")
		)
		(pad "1" smd custom
			(at 0 -0.2794 270)
			(size 0.0762 0.0762)
			(layers "F.Cu" "F.Mask" "F.Paste")
			(net "PHY_IOC_TO_SCC_44_DN")
			(options
				(clearance outline)
				(anchor circle)
			)
			(primitives
				(gr_poly
					(pts
						(arc
							(start 0.1524 -0.127)
							(mid 0.137521 -0.162921)
							(end 0.1016 -0.1778)
						)
						(arc
							(start -0.1016 -0.1778)
							(mid -0.137521 -0.162921)
							(end -0.1524 -0.127)
						)
						(arc
							(start -0.1524 0.127)
							(mid -0.137521 0.162921)
							(end -0.1016 0.1778)
						)
						(arc
							(start 0.1016 0.1778)
							(mid 0.137521 0.162921)
							(end 0.1524 0.127)
						)
					)
					(width 0)
					(fill yes)
				)
			)
		)
		(pad "2" smd custom
			(at 0 0.2794 270)
			(size 0.0762 0.0762)
			(layers "F.Cu" "F.Mask" "F.Paste")
			(net "PHY_IOC_TO_SCC_C_44_DN")
			(options
				(clearance outline)
				(anchor circle)
			)
			(primitives
				(gr_poly
					(pts
						(arc
							(start 0.1524 -0.127)
							(mid 0.137521 -0.162921)
							(end 0.1016 -0.1778)
						)
						(arc
							(start -0.1016 -0.1778)
							(mid -0.137521 -0.162921)
							(end -0.1524 -0.127)
						)
						(arc
							(start -0.1524 0.127)
							(mid -0.137521 0.162921)
							(end -0.1016 0.1778)
						)
						(arc
							(start 0.1016 0.1778)
							(mid 0.137521 0.162921)
							(end 0.1524 0.127)
						)
					)
					(width 0)
					(fill yes)
				)
			)
		)
	)
	(footprint ""
		(layer "F.Cu")
		(at 130.57378 -44.717716 180)
		(property "Reference" "C43"
			(at 0 0 180)
			(layer "F.SilkS")
			(hide yes)
			(effects
				(font
					(size 1.27 1.27)
				)
			)
		)
		(property "Value" "SCD01U16V1KX-GP"
			(at -2.8321 -1.7399 180)
			(unlocked yes)
			(layer "F.Fab")
			(hide yes)
			(effects
				(font
					(size 1.016 1.016)
					(thickness 0.1524)
				)
			)
		)
		(property "Device Type" "C0201H13"
			(at -2.8321 -3.2639 180)
			(unlocked yes)
			(layer "F.Fab")
			(hide yes)
			(effects
				(font
					(size 1.016 1.016)
					(thickness 0.1524)
				)
			)
		)
		(duplicate_pad_numbers_are_jumpers no)
		(fp_rect
			(start -0.2794 0.6477)
			(end 0.2794 -0.6477)
			(stroke
				(width 0)
				(type default)
			)
			(fill no)
			(layer "F.CrtYd")
		)
		(fp_rect
			(start -0.2794 0.6477)
			(end 0.2794 -0.6477)
			(stroke
				(width 0)
				(type default)
			)
			(fill no)
			(layer "F.Fab")
		)
		(pad "1" smd custom
			(at 0 -0.2794 180)
			(size 0.0762 0.0762)
			(layers "F.Cu" "F.Mask" "F.Paste")
			(net "PHY_IOC_TO_SCC_42_DP")
			(options
				(clearance outline)
				(anchor circle)
			)
			(primitives
				(gr_poly
					(pts
						(arc
							(start 0.1524 -0.127)
							(mid 0.137521 -0.162921)
							(end 0.1016 -0.1778)
						)
						(arc
							(start -0.1016 -0.1778)
							(mid -0.137521 -0.162921)
							(end -0.1524 -0.127)
						)
						(arc
							(start -0.1524 0.127)
							(mid -0.137521 0.162921)
							(end -0.1016 0.1778)
						)
						(arc
							(start 0.1016 0.1778)
							(mid 0.137521 0.162921)
							(end 0.1524 0.127)
						)
					)
					(width 0)
					(fill yes)
				)
			)
		)
		(pad "2" smd custom
			(at 0 0.2794 180)
			(size 0.0762 0.0762)
			(layers "F.Cu" "F.Mask" "F.Paste")
			(net "PHY_IOC_TO_SCC_C_42_DP")
			(options
				(clearance outline)
				(anchor circle)
			)
			(primitives
				(gr_poly
					(pts
						(arc
							(start 0.1524 -0.127)
							(mid 0.137521 -0.162921)
							(end 0.1016 -0.1778)
						)
						(arc
							(start -0.1016 -0.1778)
							(mid -0.137521 -0.162921)
							(end -0.1524 -0.127)
						)
						(arc
							(start -0.1524 0.127)
							(mid -0.137521 0.162921)
							(end -0.1016 0.1778)
						)
						(arc
							(start 0.1016 0.1778)
							(mid 0.137521 0.162921)
							(end 0.1524 0.127)
						)
					)
					(width 0)
					(fill yes)
				)
			)
		)
	)
	(footprint ""
		(layer "F.Cu")
		(at 190.23838 -75.46848 -90)
		(property "Reference" "R371"
			(at 0 0 270)
			(layer "F.SilkS")
			(hide yes)
			(effects
				(font
					(size 1.27 1.27)
				)
			)
		)
		(property "Value" "4K7R2F-GP"
			(at 0.064008 -3.993896 270)
			(unlocked yes)
			(layer "F.Fab")
			(hide yes)
			(effects
				(font
					(size 1.016 1.016)
					(thickness 0.1524)
				)
			)
		)
		(property "Device Type" "R402H16"
			(at 0.064008 -5.517896 270)
			(unlocked yes)
			(layer "F.Fab")
			(hide yes)
			(effects
				(font
					(size 1.016 1.016)
					(thickness 0.1524)
				)
			)
		)
		(duplicate_pad_numbers_are_jumpers no)
		(fp_line
			(start -0.508 -0.9398)
			(end -0.508 0.9398)
			(stroke
				(width 0.1524)
				(type default)
			)
			(layer "F.SilkS")
		)
		(fp_line
			(start 0.508 -0.9398)
			(end -0.508 -0.9398)
			(stroke
				(width 0.1524)
				(type default)
			)
			(layer "F.SilkS")
		)
		(fp_rect
			(start -0.508 0.9398)
			(end 0.508 -0.9398)
			(stroke
				(width 0)
				(type default)
			)
			(fill no)
			(layer "F.CrtYd")
		)
		(fp_rect
			(start -0.508 0.9398)
			(end 0.508 -0.9398)
			(stroke
				(width 0)
				(type default)
			)
			(fill no)
			(layer "F.Fab")
		)
		(pad "1" smd custom
			(at 0 -0.4445 270)
			(size 0.1397 0.1397)
			(layers "F.Cu" "F.Mask" "F.Paste")
			(net "P3V3")
			(options
				(clearance outline)
				(anchor circle)
			)
			(primitives
				(gr_poly
					(pts
						(arc
							(start -0.1778 -0.2794)
							(mid -0.249642 -0.249642)
							(end -0.2794 -0.1778)
						)
						(arc
							(start -0.2794 0.1778)
							(mid -0.249642 0.249642)
							(end -0.1778 0.2794)
						)
						(arc
							(start 0.1778 0.2794)
							(mid 0.249642 0.249642)
							(end 0.2794 0.1778)
						)
						(arc
							(start 0.2794 -0.1778)
							(mid 0.249642 -0.249642)
							(end 0.1778 -0.2794)
						)
					)
					(width 0)
					(fill yes)
				)
			)
		)
		(pad "2" smd custom
			(at 0 0.4445 270)
			(size 0.1397 0.1397)
			(layers "F.Cu" "F.Mask" "F.Paste")
			(net "TEMP2_A0")
			(options
				(clearance outline)
				(anchor circle)
			)
			(primitives
				(gr_poly
					(pts
						(arc
							(start -0.1778 -0.2794)
							(mid -0.249642 -0.249642)
							(end -0.2794 -0.1778)
						)
						(arc
							(start -0.2794 0.1778)
							(mid -0.249642 0.249642)
							(end -0.1778 0.2794)
						)
						(arc
							(start 0.1778 0.2794)
							(mid 0.249642 0.249642)
							(end 0.2794 0.1778)
						)
						(arc
							(start 0.2794 -0.1778)
							(mid 0.249642 -0.249642)
							(end 0.1778 -0.2794)
						)
					)
					(width 0)
					(fill yes)
				)
			)
		)
	)
)
